(kicad_pcb
	(version 20241229)
	(generator "pcbnew")
	(generator_version "9.0")
	(general
		(thickness 1.6642)
		(legacy_teardrops no)
	)
	(paper "A3")
	(title_block
		(title "PolarFire SoM")
		(date "2025-07-22")
		(rev "1.1.4")
		(company "Antmicro Ltd")
		(comment 1 "www.antmicro.com")
		(comment 9 "footprints 205-208 of 470")
	)
	(layers
		(0 "F.Cu" mixed)
		(4 "In1.Cu" power)
		(6 "In2.Cu" signal)
		(8 "In3.Cu" power)
		(10 "In4.Cu" signal)
		(12 "In5.Cu" power)
		(14 "In6.Cu" power)
		(16 "In7.Cu" signal)
		(18 "In8.Cu" power)
		(20 "In9.Cu" signal)
		(22 "In10.Cu" power)
		(24 "In11.Cu" signal)
		(26 "In12.Cu" signal)
		(2 "B.Cu" mixed)
		(9 "F.Adhes" user "F.Adhesive")
		(11 "B.Adhes" user "B.Adhesive")
		(13 "F.Paste" user)
		(15 "B.Paste" user)
		(5 "F.SilkS" user "F.Silkscreen")
		(7 "B.SilkS" user "B.Silkscreen")
		(1 "F.Mask" user)
		(3 "B.Mask" user)
		(17 "Dwgs.User" user "User.Drawings")
		(19 "Cmts.User" user "User.Comments")
		(21 "Eco1.User" user "User.Eco1")
		(23 "Eco2.User" user "User.Eco2")
		(25 "Edge.Cuts" user)
		(27 "Margin" user)
		(31 "F.CrtYd" user "F.Courtyard")
		(29 "B.CrtYd" user "B.Courtyard")
		(35 "F.Fab" user)
		(33 "B.Fab" user)
	)
	(footprint "antmicro-footprints:C_0402_1005Metric"
		(layer "B.Cu")
		(at 208.1 148.41 180)
		(descr "Capacitor SMD 0402")
		(tags "capacitor SMD 0402")
		(property "Reference" "C209"
			(at 4.9 18.375 0)
			(layer "B.SilkS")
			(effects
				(font
					(size 0.7 0.7)
					(thickness 0.15)
				)
				(justify left bottom mirror)
			)
		)
		(property "Value" "C_10u_10V_0402"
			(at -1.022927 -2.155213 0)
			(layer "B.Fab")
			(hide yes)
			(effects
				(font
					(size 0.7 0.7)
					(thickness 0.15)
				)
				(justify left bottom mirror)
			)
		)
		(property "Datasheet" "https://www.murata.com/products/productdetail?partno=GRM155R61A106ME11%23"
			(at 0 0 180)
			(layer "F.Fab")
			(hide yes)
			(effects
				(font
					(size 1.27 1.27)
					(thickness 0.15)
				)
			)
		)
		(property "Description" "Multilayer Ceramic Capacitors MLCC - SMD/SMT 10 uF 10 VDC 20% 0402 X5R"
			(at 0 0 180)
			(layer "F.Fab")
			(hide yes)
			(effects
				(font
					(size 1.27 1.27)
					(thickness 0.15)
				)
			)
		)
		(property "Author" "Antmicro"
			(at 416.2 296.82 0)
			(layer "B.Fab")
			(hide yes)
			(effects
				(font
					(size 1 1)
					(thickness 0.15)
				)
				(justify mirror)
			)
		)
		(property "Dielectric" "X5R"
			(at 416.2 296.82 0)
			(layer "B.Fab")
			(hide yes)
			(effects
				(font
					(size 1 1)
					(thickness 0.15)
				)
				(justify mirror)
			)
		)
		(property "License" "Apache-2.0"
			(at 416.2 296.82 0)
			(layer "B.Fab")
			(hide yes)
			(effects
				(font
					(size 1 1)
					(thickness 0.15)
				)
				(justify mirror)
			)
		)
		(property "MPN" "GRM155R61A106ME11D"
			(at 416.2 296.82 0)
			(layer "B.Fab")
			(hide yes)
			(effects
				(font
					(size 1 1)
					(thickness 0.15)
				)
				(justify mirror)
			)
		)
		(property "Manufacturer" "Murata"
			(at 416.2 296.82 0)
			(layer "B.Fab")
			(hide yes)
			(effects
				(font
					(size 1 1)
					(thickness 0.15)
				)
				(justify mirror)
			)
		)
		(property "Public" ""
			(at 416.2 296.82 0)
			(layer "B.Fab")
			(hide yes)
			(effects
				(font
					(size 1 1)
					(thickness 0.15)
				)
				(justify mirror)
			)
		)
		(property "Val" "10u"
			(at 416.2 296.82 0)
			(layer "B.Fab")
			(hide yes)
			(effects
				(font
					(size 1 1)
					(thickness 0.15)
				)
				(justify mirror)
			)
		)
		(property "Voltage" "10V"
			(at 416.2 296.82 0)
			(layer "B.Fab")
			(hide yes)
			(effects
				(font
					(size 1 1)
					(thickness 0.15)
				)
				(justify mirror)
			)
		)
		(sheetname "/MIPI CrossLink/")
		(sheetfile "crosslink.kicad_sch")
		(attr smd)
		(fp_rect
			(start -0.925 0.47)
			(end 0.925 -0.47)
			(stroke
				(width 0.05)
				(type default)
			)
			(fill no)
			(layer "B.CrtYd")
		)
		(fp_line
			(start 0.504 0.25)
			(end 0.504 -0.248)
			(stroke
				(width 0.15)
				(type solid)
			)
			(layer "B.Fab")
		)
		(fp_line
			(start 0.504 -0.248)
			(end -0.494 -0.248)
			(stroke
				(width 0.15)
				(type solid)
			)
			(layer "B.Fab")
		)
		(fp_line
			(start -0.494 0.25)
			(end 0.504 0.25)
			(stroke
				(width 0.15)
				(type solid)
			)
			(layer "B.Fab")
		)
		(fp_line
			(start -0.494 -0.248)
			(end -0.494 0.25)
			(stroke
				(width 0.15)
				(type solid)
			)
			(layer "B.Fab")
		)
		(fp_text user "${REFERENCE}"
			(at -0.939 -4.599 0)
			(layer "B.Fab")
			(effects
				(font
					(size 0.7 0.7)
					(thickness 0.15)
				)
				(justify left bottom mirror)
			)
		)
		(fp_text user "License: Apache-2.0"
			(at -0.939 -5.799 0)
			(layer "B.Fab")
			(effects
				(font
					(size 0.7 0.7)
					(thickness 0.15)
				)
				(justify left bottom mirror)
			)
		)
		(fp_text user "Author: Antmicro"
			(at -0.939 -3.399 0)
			(layer "B.Fab")
			(effects
				(font
					(size 0.7 0.7)
					(thickness 0.15)
				)
				(justify left bottom mirror)
			)
		)
		(pad "1" smd roundrect
			(at -0.48 0 180)
			(size 0.59 0.64)
			(layers "B.Cu" "B.Mask" "B.Paste")
			(roundrect_rratio 0.25)
			(net 417 "GND")
			(pintype "passive")
		)
		(pad "2" smd roundrect
			(at 0.48 0 180)
			(size 0.59 0.64)
			(layers "B.Cu" "B.Mask" "B.Paste")
			(roundrect_rratio 0.25)
			(net 205 "/MIPI CrossLink/CL_VCCA_DPHY1")
			(pintype "passive")
		)
	)
	(footprint "antmicro-footprints:C_0402_1005Metric"
		(layer "B.Cu")
		(at 201.75 145.9 -90)
		(descr "Capacitor SMD 0402")
		(tags "capacitor SMD 0402")
		(property "Reference" "C205"
			(at -3.76 -0.27 270)
			(layer "B.SilkS")
			(effects
				(font
					(size 0.7 0.7)
					(thickness 0.15)
				)
				(justify left bottom mirror)
			)
		)
		(property "Value" "C_100n_0402"
			(at -1.022927 -2.155213 90)
			(layer "B.Fab")
			(hide yes)
			(effects
				(font
					(size 0.7 0.7)
					(thickness 0.15)
				)
				(justify left bottom mirror)
			)
		)
		(property "Datasheet" "https://www.murata.com/products/productdetail?partno=GRM155R61H104KE14%23"
			(at 0 0 270)
			(layer "F.Fab")
			(hide yes)
			(effects
				(font
					(size 1.27 1.27)
					(thickness 0.15)
				)
			)
		)
		(property "Description" "SMD Multilayer Ceramic Capacitor, 0.1 µF, 50 V, 0402 [1005 Metric], ± 10%, X5R, GRM Series"
			(at 0 0 270)
			(layer "F.Fab")
			(hide yes)
			(effects
				(font
					(size 1.27 1.27)
					(thickness 0.15)
				)
			)
		)
		(property "Author" "Antmicro"
			(at 55.85 347.65 0)
			(layer "B.Fab")
			(hide yes)
			(effects
				(font
					(size 1 1)
					(thickness 0.15)
				)
				(justify mirror)
			)
		)
		(property "Dielectric" "X5R"
			(at 55.85 347.65 0)
			(layer "B.Fab")
			(hide yes)
			(effects
				(font
					(size 1 1)
					(thickness 0.15)
				)
				(justify mirror)
			)
		)
		(property "License" "Apache-2.0"
			(at 55.85 347.65 0)
			(layer "B.Fab")
			(hide yes)
			(effects
				(font
					(size 1 1)
					(thickness 0.15)
				)
				(justify mirror)
			)
		)
		(property "MPN" "GRM155R61H104KE14D"
			(at 55.85 347.65 0)
			(layer "B.Fab")
			(hide yes)
			(effects
				(font
					(size 1 1)
					(thickness 0.15)
				)
				(justify mirror)
			)
		)
		(property "Manufacturer" "Murata"
			(at 55.85 347.65 0)
			(layer "B.Fab")
			(hide yes)
			(effects
				(font
					(size 1 1)
					(thickness 0.15)
				)
				(justify mirror)
			)
		)
		(property "Public" ""
			(at 55.85 347.65 0)
			(layer "B.Fab")
			(hide yes)
			(effects
				(font
					(size 1 1)
					(thickness 0.15)
				)
				(justify mirror)
			)
		)
		(property "Val" "100n"
			(at 55.85 347.65 0)
			(layer "B.Fab")
			(hide yes)
			(effects
				(font
					(size 1 1)
					(thickness 0.15)
				)
				(justify mirror)
			)
		)
		(property "Voltage" "50V"
			(at 55.85 347.65 0)
			(layer "B.Fab")
			(hide yes)
			(effects
				(font
					(size 1 1)
					(thickness 0.15)
				)
				(justify mirror)
			)
		)
		(sheetname "/MIPI CrossLink/")
		(sheetfile "crosslink.kicad_sch")
		(attr smd)
		(fp_rect
			(start -0.925 0.47)
			(end 0.925 -0.47)
			(stroke
				(width 0.05)
				(type default)
			)
			(fill no)
			(layer "B.CrtYd")
		)
		(fp_line
			(start -0.494 0.25)
			(end 0.504 0.25)
			(stroke
				(width 0.15)
				(type solid)
			)
			(layer "B.Fab")
		)
		(fp_line
			(start 0.504 0.25)
			(end 0.504 -0.248)
			(stroke
				(width 0.15)
				(type solid)
			)
			(layer "B.Fab")
		)
		(fp_line
			(start -0.494 -0.248)
			(end -0.494 0.25)
			(stroke
				(width 0.15)
				(type solid)
			)
			(layer "B.Fab")
		)
		(fp_line
			(start 0.504 -0.248)
			(end -0.494 -0.248)
			(stroke
				(width 0.15)
				(type solid)
			)
			(layer "B.Fab")
		)
		(fp_text user "Author: Antmicro"
			(at -0.939 -3.399 90)
			(layer "B.Fab")
			(effects
				(font
					(size 0.7 0.7)
					(thickness 0.15)
				)
				(justify left bottom mirror)
			)
		)
		(fp_text user "${REFERENCE}"
			(at -0.939 -4.599 90)
			(layer "B.Fab")
			(effects
				(font
					(size 0.7 0.7)
					(thickness 0.15)
				)
				(justify left bottom mirror)
			)
		)
		(fp_text user "License: Apache-2.0"
			(at -0.939 -5.799 90)
			(layer "B.Fab")
			(effects
				(font
					(size 0.7 0.7)
					(thickness 0.15)
				)
				(justify left bottom mirror)
			)
		)
		(pad "1" smd roundrect
			(at -0.48 0 270)
			(size 0.59 0.64)
			(layers "B.Cu" "B.Mask" "B.Paste")
			(roundrect_rratio 0.25)
			(net 417 "GND")
			(pintype "passive")
		)
		(pad "2" smd roundrect
			(at 0.48 0 270)
			(size 0.59 0.64)
			(layers "B.Cu" "B.Mask" "B.Paste")
			(roundrect_rratio 0.25)
			(net 191 "/MIPI CrossLink/CL_VCCIO2")
			(pintype "passive")
		)
	)
	(footprint "antmicro-footprints:R_0402_1005Metric"
		(layer "B.Cu")
		(at 213.415 146.1 180)
		(descr "Resistor SMD 0402")
		(tags "resistor SMD 0402")
		(property "Reference" "R166"
			(at -1.21 -2.45 0)
			(layer "B.SilkS")
			(effects
				(font
					(size 0.7 0.7)
					(thickness 0.15)
				)
				(justify left bottom mirror)
			)
		)
		(property "Value" "R_12k_0402"
			(at -1.011843 -1.772047 0)
			(layer "B.Fab")
			(hide yes)
			(effects
				(font
					(size 0.7 0.7)
					(thickness 0.15)
				)
				(justify left bottom mirror)
			)
		)
		(property "Datasheet" "https://www.bourns.com/docs/product-datasheets/cr.pdf"
			(at 0 0 180)
			(layer "F.Fab")
			(hide yes)
			(effects
				(font
					(size 1.27 1.27)
					(thickness 0.15)
				)
			)
		)
		(property "Description" "SMD Chip Resistor, 12 kohm, ± 1%, 62.5 mW, 0402 [1005 Metric], Thick Film, General Purpose"
			(at 0 0 180)
			(layer "F.Fab")
			(hide yes)
			(effects
				(font
					(size 1.27 1.27)
					(thickness 0.15)
				)
			)
		)
		(property "Author" "Antmicro"
			(at 426.83 292.2 0)
			(layer "B.Fab")
			(hide yes)
			(effects
				(font
					(size 1 1)
					(thickness 0.15)
				)
				(justify mirror)
			)
		)
		(property "License" "Apache-2.0"
			(at 426.83 292.2 0)
			(layer "B.Fab")
			(hide yes)
			(effects
				(font
					(size 1 1)
					(thickness 0.15)
				)
				(justify mirror)
			)
		)
		(property "MPN" "CR0402-FX-1202GLF"
			(at 426.83 292.2 0)
			(layer "B.Fab")
			(hide yes)
			(effects
				(font
					(size 1 1)
					(thickness 0.15)
				)
				(justify mirror)
			)
		)
		(property "Manufacturer" "Bourns"
			(at 426.83 292.2 0)
			(layer "B.Fab")
			(hide yes)
			(effects
				(font
					(size 1 1)
					(thickness 0.15)
				)
				(justify mirror)
			)
		)
		(property "Public" ""
			(at 426.83 292.2 0)
			(layer "B.Fab")
			(hide yes)
			(effects
				(font
					(size 1 1)
					(thickness 0.15)
				)
				(justify mirror)
			)
		)
		(property "Tolerance" "1%"
			(at 426.83 292.2 0)
			(layer "B.Fab")
			(hide yes)
			(effects
				(font
					(size 1 1)
					(thickness 0.15)
				)
				(justify mirror)
			)
		)
		(property "Val" "12k"
			(at 426.83 292.2 0)
			(layer "B.Fab")
			(hide yes)
			(effects
				(font
					(size 1 1)
					(thickness 0.15)
				)
				(justify mirror)
			)
		)
		(sheetname "/USB/")
		(sheetfile "usb.kicad_sch")
		(attr smd)
		(fp_rect
			(start -0.925 0.47)
			(end 0.925 -0.47)
			(stroke
				(width 0.05)
				(type default)
			)
			(fill no)
			(layer "B.CrtYd")
		)
		(fp_rect
			(start -0.5 0.25)
			(end 0.5 -0.25)
			(stroke
				(width 0.15)
				(type solid)
			)
			(fill no)
			(layer "B.Fab")
		)
		(fp_text user "License: Apache-2.0"
			(at -0.95 -5.169 0)
			(layer "B.Fab")
			(effects
				(font
					(size 0.7 0.7)
					(thickness 0.15)
				)
				(justify left bottom mirror)
			)
		)
		(fp_text user "${REFERENCE}"
			(at -0.95 -3.168 0)
			(layer "B.Fab")
			(effects
				(font
					(size 0.7 0.7)
					(thickness 0.15)
				)
				(justify left bottom mirror)
			)
		)
		(fp_text user "Author: Antmicro"
			(at -0.95 -4.169 0)
			(layer "B.Fab")
			(effects
				(font
					(size 0.7 0.7)
					(thickness 0.15)
				)
				(justify left bottom mirror)
			)
		)
		(pad "1" smd roundrect
			(at -0.48 0 180)
			(size 0.59 0.64)
			(layers "B.Cu" "B.Mask" "B.Paste")
			(roundrect_rratio 0.25)
			(net 417 "GND")
			(pintype "passive")
		)
		(pad "2" smd roundrect
			(at 0.48 0 180)
			(size 0.59 0.64)
			(layers "B.Cu" "B.Mask" "B.Paste")
			(roundrect_rratio 0.25)
			(net 325 "Net-(U28-R_{BIAS})")
			(pintype "passive")
		)
	)
	(footprint "antmicro-footprints:R_0402_1005Metric"
		(layer "B.Cu")
		(at 179.75 145.55 90)
		(descr "Resistor SMD 0402")
		(tags "resistor SMD 0402")
		(property "Reference" "R83"
			(at -2.85 2.2 315)
			(layer "B.SilkS")
			(effects
				(font
					(size 0.7 0.7)
					(thickness 0.15)
				)
				(justify left bottom mirror)
			)
		)
		(property "Value" "R_10k_0402"
			(at -1.011843 -1.772047 270)
			(layer "B.Fab")
			(hide yes)
			(effects
				(font
					(size 0.7 0.7)
					(thickness 0.15)
				)
				(justify left bottom mirror)
			)
		)
		(property "Datasheet" "https://www.bourns.com/docs/product-datasheets/cr.pdf"
			(at 0 0 90)
			(layer "F.Fab")
			(hide yes)
			(effects
				(font
					(size 1.27 1.27)
					(thickness 0.15)
				)
			)
		)
		(property "Description" "SMD Chip Resistor, 10 kohm, ± 1%, 62.5 mW, 0402 [1005 Metric], Thick Film, General Purpose"
			(at 0 0 90)
			(layer "F.Fab")
			(hide yes)
			(effects
				(font
					(size 1.27 1.27)
					(thickness 0.15)
				)
			)
		)
		(property "Author" "Antmicro"
			(at 325.3 -34.2 0)
			(layer "B.Fab")
			(hide yes)
			(effects
				(font
					(size 1 1)
					(thickness 0.15)
				)
				(justify mirror)
			)
		)
		(property "License" "Apache-2.0"
			(at 325.3 -34.2 0)
			(layer "B.Fab")
			(hide yes)
			(effects
				(font
					(size 1 1)
					(thickness 0.15)
				)
				(justify mirror)
			)
		)
		(property "MPN" "CR0402-FX-1002GLF"
			(at 325.3 -34.2 0)
			(layer "B.Fab")
			(hide yes)
			(effects
				(font
					(size 1 1)
					(thickness 0.15)
				)
				(justify mirror)
			)
		)
		(property "Manufacturer" "Bourns"
			(at 325.3 -34.2 0)
			(layer "B.Fab")
			(hide yes)
			(effects
				(font
					(size 1 1)
					(thickness 0.15)
				)
				(justify mirror)
			)
		)
		(property "Public" ""
			(at 325.3 -34.2 0)
			(layer "B.Fab")
			(hide yes)
			(effects
				(font
					(size 1 1)
					(thickness 0.15)
				)
				(justify mirror)
			)
		)
		(property "Tolerance" "1%"
			(at 325.3 -34.2 0)
			(layer "B.Fab")
			(hide yes)
			(effects
				(font
					(size 1 1)
					(thickness 0.15)
				)
				(justify mirror)
			)
		)
		(property "Val" "10k"
			(at 325.3 -34.2 0)
			(layer "B.Fab")
			(hide yes)
			(effects
				(font
					(size 1 1)
					(thickness 0.15)
				)
				(justify mirror)
			)
		)
		(sheetname "/Supply/")
		(sheetfile "supply.kicad_sch")
		(attr smd)
		(fp_rect
			(start -0.925 0.47)
			(end 0.925 -0.47)
			(stroke
				(width 0.05)
				(type default)
			)
			(fill no)
			(layer "B.CrtYd")
		)
		(fp_rect
			(start -0.5 0.25)
			(end 0.5 -0.25)
			(stroke
				(width 0.15)
				(type solid)
			)
			(fill no)
			(layer "B.Fab")
		)
		(fp_text user "${REFERENCE}"
			(at -0.95 -3.168 270)
			(layer "B.Fab")
			(effects
				(font
					(size 0.7 0.7)
					(thickness 0.15)
				)
				(justify left bottom mirror)
			)
		)
		(fp_text user "Author: Antmicro"
			(at -0.95 -4.169 270)
			(layer "B.Fab")
			(effects
				(font
					(size 0.7 0.7)
					(thickness 0.15)
				)
				(justify left bottom mirror)
			)
		)
		(fp_text user "License: Apache-2.0"
			(at -0.95 -5.169 270)
			(layer "B.Fab")
			(effects
				(font
					(size 0.7 0.7)
					(thickness 0.15)
				)
				(justify left bottom mirror)
			)
		)
		(pad "1" smd roundrect
			(at -0.48 0 90)
			(size 0.59 0.64)
			(layers "B.Cu" "B.Mask" "B.Paste")
			(roundrect_rratio 0.25)
			(net 656 "/Supply/PG")
			(pintype "passive")
		)
		(pad "2" smd roundrect
			(at 0.48 0 90)
			(size 0.59 0.64)
			(layers "B.Cu" "B.Mask" "B.Paste")
			(roundrect_rratio 0.25)
			(net 90 "+5V")
			(pintype "passive")
		)
	)
)
